# T6G (Grand Teton) — schematic netlist excerpt (pin names and nets, part order shuffled) for the footprints in the layout excerpt that follows; sources: Cadence DE-HDL packaged netlist, KiCad conversion of 04192023_DAF0TMB3IC0_F0TG_MB_C_brd_V02_OCP.brd

C184  Q_CAP  0.1UF 10V 10% X7S  pkg C0201  page 323 : A = P0V9_CPU1_RT0_2A ; B = GND
C2470  Q_CAP  22UF 4V 20% X6S  pkg C0402  page 74 : A = PVDDCR_SOC_P1 ; B = GND
R3118  Q_RES  86.6K 1% EMPTY  pkg 0402LF  page 190 : A = P3V3_AUX_EN ; B = GND

(kicad_pcb
	(version 20260206)
	(generator "pcbnew")
	(generator_version "10.0")
	(general
		(thickness 1.6)
		(legacy_teardrops no)
	)
	(paper "A4")
	(title_block
		(title "04192023_DAF0TMB3IC0_F0TG_MB_C_brd_V02_OCP.brd")
		(comment 1 "Grand Teton / footprints 5153-5155 of 8354")
	)
	(layers
		(0 "F.Cu" signal "TOP")
		(4 "In1.Cu" signal "GND")
		(6 "In2.Cu" signal "IN1")
		(8 "In3.Cu" signal "GND1")
		(10 "In4.Cu" signal "IN2")
		(12 "In5.Cu" signal "GND2")
		(14 "In6.Cu" signal "IN3")
		(16 "In7.Cu" signal "GND3")
		(18 "In8.Cu" signal "VCC")
		(20 "In9.Cu" signal "VCC1")
		(22 "In10.Cu" signal "GND4")
		(24 "In11.Cu" signal "IN4")
		(26 "In12.Cu" signal "GND5")
		(28 "In13.Cu" signal "IN5")
		(30 "In14.Cu" signal "GND6")
		(32 "In15.Cu" signal "IN6")
		(34 "In16.Cu" signal "GND7")
		(2 "B.Cu" signal "BOTTOM")
		(9 "F.Adhes" user "F.Adhesive")
		(11 "B.Adhes" user "B.Adhesive")
		(13 "F.Paste" user "Package Geometry/Pastemask Top")
		(15 "B.Paste" user "Package Geometry/Pastemask Bottom")
		(5 "F.SilkS" user "Ref Des/Silkscreen Top")
		(7 "B.SilkS" user "Ref Des/Silkscreen Bottom")
		(1 "F.Mask" user "Board Geometry/Soldermask Top")
		(3 "B.Mask" user "Board Geometry/Soldermask Bottom")
		(17 "Dwgs.User" user "User.Drawings")
		(19 "Cmts.User" user "User.Comments")
		(21 "Eco1.User" user "User.Eco1")
		(23 "Eco2.User" user "User.Eco2")
		(25 "Edge.Cuts" user "Board Geometry/Outline")
		(27 "Margin" user)
		(31 "F.CrtYd" user "Package Geometry/Place Bound Top")
		(29 "B.CrtYd" user "Package Geometry/Place Bound Bottom")
		(35 "F.Fab" user "Ref Des/Assembly Top")
		(33 "B.Fab" user "Ref Des/Assembly Bottom")
	)
	(footprint ""
		(layer "B.Cu")
		(at 455.07783 -48.106838 -90)
		(property "Reference" "R3118"
			(at 0 0 90)
			(layer "B.SilkS")
			(hide yes)
			(effects
				(font
					(size 1.27 1.27)
				)
				(justify mirror)
			)
		)
		(property "Value" ""
			(at 0 0 90)
			(layer "B.Fab")
			(effects
				(font
					(size 1.27 1.27)
				)
				(justify mirror)
			)
		)
		(duplicate_pad_numbers_are_jumpers no)
		(fp_line
			(start -0.7874 0.4064)
			(end 0.7874 0.4064)
			(stroke
				(width 0.1524)
				(type default)
			)
			(layer "B.SilkS")
		)
		(fp_line
			(start 0.7874 0.4064)
			(end 0.7874 -0.4064)
			(stroke
				(width 0.1524)
				(type default)
			)
			(layer "B.SilkS")
		)
		(fp_line
			(start -0.7874 -0.4064)
			(end -0.7874 0.4064)
			(stroke
				(width 0.1524)
				(type default)
			)
			(layer "B.SilkS")
		)
		(fp_line
			(start 0.7874 -0.4064)
			(end -0.7874 -0.4064)
			(stroke
				(width 0.1524)
				(type default)
			)
			(layer "B.SilkS")
		)
		(fp_line
			(start -0.67945 0.3048)
			(end -0.120396 0.3048)
			(stroke
				(width 0.1)
				(type default)
			)
			(layer "B.Fab")
		)
		(fp_line
			(start -0.120396 0.3048)
			(end -0.120396 0.2794)
			(stroke
				(width 0.1)
				(type default)
			)
			(layer "B.Fab")
		)
		(fp_line
			(start 0.12065 0.3048)
			(end 0.67945 0.3048)
			(stroke
				(width 0.1)
				(type default)
			)
			(layer "B.Fab")
		)
		(fp_line
			(start 0.67945 0.3048)
			(end 0.67945 -0.305054)
			(stroke
				(width 0.1)
				(type default)
			)
			(layer "B.Fab")
		)
		(fp_line
			(start -0.120396 0.2794)
			(end 0.12065 0.2794)
			(stroke
				(width 0.1)
				(type default)
			)
			(layer "B.Fab")
		)
		(fp_line
			(start 0.12065 0.2794)
			(end 0.12065 0.3048)
			(stroke
				(width 0.1)
				(type default)
			)
			(layer "B.Fab")
		)
		(fp_line
			(start -0.12065 -0.2794)
			(end -0.12065 -0.3048)
			(stroke
				(width 0.1)
				(type default)
			)
			(layer "B.Fab")
		)
		(fp_line
			(start 0.12065 -0.2794)
			(end -0.12065 -0.2794)
			(stroke
				(width 0.1)
				(type default)
			)
			(layer "B.Fab")
		)
		(fp_line
			(start -0.67945 -0.3048)
			(end -0.67945 0.3048)
			(stroke
				(width 0.1)
				(type default)
			)
			(layer "B.Fab")
		)
		(fp_line
			(start -0.12065 -0.3048)
			(end -0.67945 -0.3048)
			(stroke
				(width 0.1)
				(type default)
			)
			(layer "B.Fab")
		)
		(fp_line
			(start 0.12065 -0.305054)
			(end 0.12065 -0.2794)
			(stroke
				(width 0.1)
				(type default)
			)
			(layer "B.Fab")
		)
		(fp_line
			(start 0.67945 -0.305054)
			(end 0.12065 -0.305054)
			(stroke
				(width 0.1)
				(type default)
			)
			(layer "B.Fab")
		)
		(pad "1" smd circle
			(at 0.40005 0 90)
			(size 0 0)
			(layers "B.Cu" "B.Mask" "B.Paste")
			(net "P3V3_AUX_EN")
		)
		(pad "2" smd circle
			(at -0.40005 0 90)
			(size 0 0)
			(layers "B.Cu" "B.Mask" "B.Paste")
			(net "GND")
		)
	)
	(footprint ""
		(layer "B.Cu")
		(at 49.91862 -388.011162 -90)
		(property "Reference" "C184"
			(at 0 0 90)
			(layer "B.SilkS")
			(hide yes)
			(effects
				(font
					(size 1.27 1.27)
				)
				(justify mirror)
			)
		)
		(property "Value" ""
			(at 0 0 90)
			(layer "B.Fab")
			(effects
				(font
					(size 1.27 1.27)
				)
				(justify mirror)
			)
		)
		(duplicate_pad_numbers_are_jumpers no)
		(fp_line
			(start -0.299974 0.150114)
			(end 0.299974 0.150114)
			(stroke
				(width 0.1)
				(type default)
			)
			(layer "B.Fab")
		)
		(fp_line
			(start 0.299974 0.150114)
			(end 0.299974 -0.150114)
			(stroke
				(width 0.1)
				(type default)
			)
			(layer "B.Fab")
		)
		(fp_line
			(start -0.299974 -0.150114)
			(end -0.299974 0.150114)
			(stroke
				(width 0.1)
				(type default)
			)
			(layer "B.Fab")
		)
		(fp_line
			(start 0.299974 -0.150114)
			(end -0.299974 -0.150114)
			(stroke
				(width 0.1)
				(type default)
			)
			(layer "B.Fab")
		)
		(pad "1" smd rect
			(at 0.2667 0 90)
			(size 0.3048 0.381)
			(layers "B.Cu" "B.Mask" "B.Paste")
			(net "P0V9_CPU1_RT0_2A")
		)
		(pad "2" smd rect
			(at -0.2667 0 90)
			(size 0.3048 0.381)
			(layers "B.Cu" "B.Mask" "B.Paste")
			(net "GND")
		)
	)
	(footprint ""
		(layer "B.Cu")
		(at 101.894386 -255.845564)
		(property "Reference" "C2470"
			(at 0 0 0)
			(layer "B.SilkS")
			(hide yes)
			(effects
				(font
					(size 1.27 1.27)
				)
				(justify mirror)
			)
		)
		(property "Value" ""
			(at 0 0 0)
			(layer "B.Fab")
			(effects
				(font
					(size 1.27 1.27)
				)
				(justify mirror)
			)
		)
		(duplicate_pad_numbers_are_jumpers no)
		(fp_line
			(start -0.7874 -0.4064)
			(end -0.7874 0.4064)
			(stroke
				(width 0.1524)
				(type default)
			)
			(layer "B.SilkS")
		)
		(fp_line
			(start -0.7874 0.4064)
			(end 0.7874 0.4064)
			(stroke
				(width 0.1524)
				(type default)
			)
			(layer "B.SilkS")
		)
		(fp_line
			(start 0.7874 -0.4064)
			(end -0.7874 -0.4064)
			(stroke
				(width 0.1524)
				(type default)
			)
			(layer "B.SilkS")
		)
		(fp_line
			(start 0.7874 0.4064)
			(end 0.7874 -0.4064)
			(stroke
				(width 0.1524)
				(type default)
			)
			(layer "B.SilkS")
		)
		(fp_line
			(start -0.67945 -0.3048)
			(end -0.67945 0.3048)
			(stroke
				(width 0.1)
				(type default)
			)
			(layer "B.Fab")
		)
		(fp_line
			(start -0.67945 0.3048)
			(end -0.120396 0.3048)
			(stroke
				(width 0.1)
				(type default)
			)
			(layer "B.Fab")
		)
		(fp_line
			(start -0.12065 -0.3048)
			(end -0.67945 -0.3048)
			(stroke
				(width 0.1)
				(type default)
			)
			(layer "B.Fab")
		)
		(fp_line
			(start -0.12065 -0.2794)
			(end -0.12065 -0.3048)
			(stroke
				(width 0.1)
				(type default)
			)
			(layer "B.Fab")
		)
		(fp_line
			(start -0.120396 0.2794)
			(end 0.12065 0.2794)
			(stroke
				(width 0.1)
				(type default)
			)
			(layer "B.Fab")
		)
		(fp_line
			(start -0.120396 0.3048)
			(end -0.120396 0.2794)
			(stroke
				(width 0.1)
				(type default)
			)
			(layer "B.Fab")
		)
		(fp_line
			(start 0.12065 -0.305054)
			(end 0.12065 -0.2794)
			(stroke
				(width 0.1)
				(type default)
			)
			(layer "B.Fab")
		)
		(fp_line
			(start 0.12065 -0.2794)
			(end -0.12065 -0.2794)
			(stroke
				(width 0.1)
				(type default)
			)
			(layer "B.Fab")
		)
		(fp_line
			(start 0.12065 0.2794)
			(end 0.12065 0.3048)
			(stroke
				(width 0.1)
				(type default)
			)
			(layer "B.Fab")
		)
		(fp_line
			(start 0.12065 0.3048)
			(end 0.67945 0.3048)
			(stroke
				(width 0.1)
				(type default)
			)
			(layer "B.Fab")
		)
		(fp_line
			(start 0.67945 -0.305054)
			(end 0.12065 -0.305054)
			(stroke
				(width 0.1)
				(type default)
			)
			(layer "B.Fab")
		)
		(fp_line
			(start 0.67945 0.3048)
			(end 0.67945 -0.305054)
			(stroke
				(width 0.1)
				(type default)
			)
			(layer "B.Fab")
		)
		(pad "1" smd circle
			(at 0.40005 0 180)
			(size 0 0)
			(layers "B.Cu" "B.Mask" "B.Paste")
			(net "PVDDCR_SOC_P1")
		)
		(pad "2" smd circle
			(at -0.40005 0 180)
			(size 0 0)
			(layers "B.Cu" "B.Mask" "B.Paste")
			(net "GND")
		)
	)
)
